(kicad_pcb
	(version 20260206)
	(generator "pcbnew")
	(generator_version "10.0")
	(general
		(thickness 1.6)
		(legacy_teardrops no)
	)
	(paper "A4")
	(title_block
		(title "panther-plus-userver — 13130-1b_20150205.brd")
		(comment 1 "Honey Badger (Wiwynn) / footprints 278-281 of 1509")
	)
	(layers
		(0 "F.Cu" signal "TOP")
		(4 "In1.Cu" signal "L2")
		(6 "In2.Cu" signal "L3")
		(8 "In3.Cu" signal "L4")
		(10 "In4.Cu" signal "L5")
		(12 "In5.Cu" signal "L6")
		(14 "In6.Cu" signal "L7")
		(16 "In7.Cu" signal "L8")
		(18 "In8.Cu" signal "L9")
		(20 "In9.Cu" signal "L10")
		(22 "In10.Cu" signal "L11")
		(2 "B.Cu" signal "BOTTOM")
		(9 "F.Adhes" user "F.Adhesive")
		(11 "B.Adhes" user "B.Adhesive")
		(13 "F.Paste" user "Package Geometry/Pastemask Top")
		(15 "B.Paste" user "Package Geometry/Pastemask Bottom")
		(5 "F.SilkS" user "Ref Des/Silkscreen Top")
		(7 "B.SilkS" user "Ref Des/Silkscreen Bottom")
		(1 "F.Mask" user "Board Geometry/Soldermask Top")
		(3 "B.Mask" user "Board Geometry/Soldermask Bottom")
		(17 "Dwgs.User" user "User.Drawings")
		(19 "Cmts.User" user "User.Comments")
		(21 "Eco1.User" user "User.Eco1")
		(23 "Eco2.User" user "User.Eco2")
		(25 "Edge.Cuts" user "Board Geometry/Outline")
		(27 "Margin" user)
		(31 "F.CrtYd" user "Package Geometry/Place Bound Top")
		(29 "B.CrtYd" user "Package Geometry/Place Bound Bottom")
		(35 "F.Fab" user "Ref Des/Assembly Top")
		(33 "B.Fab" user "Ref Des/Assembly Bottom")
	)
	(footprint ""
		(layer "F.Cu")
		(at 136.398 -59.4614 90)
		(property "Reference" "PC43"
			(at 0 0 90)
			(layer "F.SilkS")
			(hide yes)
			(effects
				(font
					(size 1.27 1.27)
				)
			)
		)
		(property "Value" "SC1KP50V2KX-1GP"
			(at 1.1811 -2.7051 90)
			(unlocked yes)
			(layer "F.Fab")
			(hide yes)
			(effects
				(font
					(size 1.016 1.016)
					(thickness 0.1524)
				)
			)
		)
		(property "Device Type" "C402H22"
			(at 1.1811 -4.2291 90)
			(unlocked yes)
			(layer "F.Fab")
			(hide yes)
			(effects
				(font
					(size 1.016 1.016)
					(thickness 0.1524)
				)
			)
		)
		(duplicate_pad_numbers_are_jumpers no)
		(fp_rect
			(start -0.381 0.7366)
			(end 0.381 -0.7366)
			(stroke
				(width 0)
				(type default)
			)
			(fill no)
			(layer "F.CrtYd")
		)
		(fp_rect
			(start -0.381 0.7366)
			(end 0.381 -0.7366)
			(stroke
				(width 0)
				(type default)
			)
			(fill no)
			(layer "F.Fab")
		)
		(pad "1" smd custom
			(at 0 -0.4572 90)
			(size 0.1143 0.1143)
			(layers "F.Cu" "F.Mask" "F.Paste")
			(net "PV_VTT_DDR_REFIN")
			(options
				(clearance outline)
				(anchor circle)
			)
			(primitives
				(gr_poly
					(pts
						(arc
							(start -0.254 -0.1778)
							(mid -0.239121 -0.213721)
							(end -0.2032 -0.2286)
						)
						(arc
							(start 0.2032 -0.2286)
							(mid 0.239121 -0.213721)
							(end 0.254 -0.1778)
						)
						(arc
							(start 0.254 0.1778)
							(mid 0.239121 0.213721)
							(end 0.2032 0.2286)
						)
						(arc
							(start -0.2032 0.2286)
							(mid -0.239121 0.213721)
							(end -0.254 0.1778)
						)
					)
					(width 0)
					(fill yes)
				)
			)
		)
		(pad "2" smd custom
			(at 0 0.4572 90)
			(size 0.1143 0.1143)
			(layers "F.Cu" "F.Mask" "F.Paste")
			(net "GND")
			(options
				(clearance outline)
				(anchor circle)
			)
			(primitives
				(gr_poly
					(pts
						(arc
							(start -0.254 -0.1778)
							(mid -0.239121 -0.213721)
							(end -0.2032 -0.2286)
						)
						(arc
							(start 0.2032 -0.2286)
							(mid 0.239121 -0.213721)
							(end 0.254 -0.1778)
						)
						(arc
							(start 0.254 0.1778)
							(mid 0.239121 0.213721)
							(end 0.2032 0.2286)
						)
						(arc
							(start -0.2032 0.2286)
							(mid -0.239121 0.213721)
							(end -0.254 0.1778)
						)
					)
					(width 0)
					(fill yes)
				)
			)
		)
	)
	(footprint ""
		(layer "F.Cu")
		(at 183.642 -38.1 -90)
		(property "Reference" "PR131"
			(at 0 0 270)
			(layer "F.SilkS")
			(hide yes)
			(effects
				(font
					(size 1.27 1.27)
				)
			)
		)
		(property "Value" "0R2J-2-GP"
			(at 1.7907 -1.1176 270)
			(unlocked yes)
			(layer "F.Fab")
			(hide yes)
			(effects
				(font
					(size 1.016 1.016)
					(thickness 0.1524)
				)
			)
		)
		(property "Device Type" "R402H16"
			(at 1.7907 -2.6416 270)
			(unlocked yes)
			(layer "F.Fab")
			(hide yes)
			(effects
				(font
					(size 1.016 1.016)
					(thickness 0.1524)
				)
			)
		)
		(duplicate_pad_numbers_are_jumpers no)
		(fp_rect
			(start -0.381 0.8382)
			(end 0.381 -0.8382)
			(stroke
				(width 0)
				(type default)
			)
			(fill no)
			(layer "F.CrtYd")
		)
		(fp_rect
			(start -0.381 0.8382)
			(end 0.381 -0.8382)
			(stroke
				(width 0)
				(type default)
			)
			(fill no)
			(layer "F.Fab")
		)
		(pad "1" smd custom
			(at 0 -0.4318 270)
			(size 0.127 0.127)
			(layers "F.Cu" "F.Mask" "F.Paste")
			(net "SVID_A_ALERT#")
			(options
				(clearance outline)
				(anchor circle)
			)
			(primitives
				(gr_poly
					(pts
						(arc
							(start -0.2032 -0.2794)
							(mid -0.239121 -0.264521)
							(end -0.254 -0.2286)
						)
						(arc
							(start -0.254 0.2286)
							(mid -0.239121 0.264521)
							(end -0.2032 0.2794)
						)
						(arc
							(start 0.2032 0.2794)
							(mid 0.239121 0.264521)
							(end 0.254 0.2286)
						)
						(arc
							(start 0.254 -0.2286)
							(mid 0.239121 -0.264521)
							(end 0.2032 -0.2794)
						)
					)
					(width 0)
					(fill yes)
				)
			)
		)
		(pad "2" smd custom
			(at 0 0.4318 270)
			(size 0.127 0.127)
			(layers "F.Cu" "F.Mask" "F.Paste")
			(net "SVID_CPU_ALERT#")
			(options
				(clearance outline)
				(anchor circle)
			)
			(primitives
				(gr_poly
					(pts
						(arc
							(start -0.2032 -0.2794)
							(mid -0.239121 -0.264521)
							(end -0.254 -0.2286)
						)
						(arc
							(start -0.254 0.2286)
							(mid -0.239121 0.264521)
							(end -0.2032 0.2794)
						)
						(arc
							(start 0.2032 0.2794)
							(mid 0.239121 0.264521)
							(end 0.254 0.2286)
						)
						(arc
							(start 0.254 -0.2286)
							(mid 0.239121 -0.264521)
							(end 0.2032 -0.2794)
						)
					)
					(width 0)
					(fill yes)
				)
			)
		)
	)
	(footprint ""
		(layer "F.Cu")
		(at 184.0738 -31.7246)
		(property "Reference" "PC103"
			(at 0 0 0)
			(layer "F.SilkS")
			(hide yes)
			(effects
				(font
					(size 1.27 1.27)
				)
			)
		)
		(property "Value" "SC1KP50V2KX-1GP"
			(at 1.8923 -1.2065 0)
			(unlocked yes)
			(layer "F.Fab")
			(hide yes)
			(effects
				(font
					(size 1.016 1.016)
					(thickness 0.1524)
				)
			)
		)
		(property "Device Type" "C402H22"
			(at 1.8923 -2.7305 0)
			(unlocked yes)
			(layer "F.Fab")
			(hide yes)
			(effects
				(font
					(size 1.016 1.016)
					(thickness 0.1524)
				)
			)
		)
		(duplicate_pad_numbers_are_jumpers no)
		(fp_rect
			(start -0.381 0.7366)
			(end 0.381 -0.7366)
			(stroke
				(width 0)
				(type default)
			)
			(fill no)
			(layer "F.CrtYd")
		)
		(fp_rect
			(start -0.381 0.7366)
			(end 0.381 -0.7366)
			(stroke
				(width 0)
				(type default)
			)
			(fill no)
			(layer "F.Fab")
		)
		(pad "1" smd custom
			(at 0 -0.4572)
			(size 0.1143 0.1143)
			(layers "F.Cu" "F.Mask" "F.Paste")
			(net "VR_PVDDR_A_VW")
			(options
				(clearance outline)
				(anchor circle)
			)
			(primitives
				(gr_poly
					(pts
						(arc
							(start -0.254 -0.1778)
							(mid -0.239121 -0.213721)
							(end -0.2032 -0.2286)
						)
						(arc
							(start 0.2032 -0.2286)
							(mid 0.239121 -0.213721)
							(end 0.254 -0.1778)
						)
						(arc
							(start 0.254 0.1778)
							(mid 0.239121 0.213721)
							(end 0.2032 0.2286)
						)
						(arc
							(start -0.2032 0.2286)
							(mid -0.239121 0.213721)
							(end -0.254 0.1778)
						)
					)
					(width 0)
					(fill yes)
				)
			)
		)
		(pad "2" smd custom
			(at 0 0.4572)
			(size 0.1143 0.1143)
			(layers "F.Cu" "F.Mask" "F.Paste")
			(net "VR_PVDDR_A_COMP")
			(options
				(clearance outline)
				(anchor circle)
			)
			(primitives
				(gr_poly
					(pts
						(arc
							(start -0.254 -0.1778)
							(mid -0.239121 -0.213721)
							(end -0.2032 -0.2286)
						)
						(arc
							(start 0.2032 -0.2286)
							(mid 0.239121 -0.213721)
							(end 0.254 -0.1778)
						)
						(arc
							(start 0.254 0.1778)
							(mid 0.239121 0.213721)
							(end 0.2032 0.2286)
						)
						(arc
							(start -0.2032 0.2286)
							(mid -0.239121 0.213721)
							(end -0.254 0.1778)
						)
					)
					(width 0)
					(fill yes)
				)
			)
		)
	)
	(footprint ""
		(layer "F.Cu")
		(at 6.6294 -25.527 180)
		(property "Reference" "PR114"
			(at 0 0 180)
			(layer "F.SilkS")
			(hide yes)
			(effects
				(font
					(size 1.27 1.27)
				)
			)
		)
		(property "Value" "0R3J-0-U-GP"
			(at -0.0254 -2.0193 180)
			(unlocked yes)
			(layer "F.Fab")
			(hide yes)
			(effects
				(font
					(size 1.016 1.016)
					(thickness 0.1524)
				)
			)
		)
		(property "Device Type" "R603H22"
			(at -0.0254 -3.5433 180)
			(unlocked yes)
			(layer "F.Fab")
			(hide yes)
			(effects
				(font
					(size 1.016 1.016)
					(thickness 0.1524)
				)
			)
		)
		(duplicate_pad_numbers_are_jumpers no)
		(fp_line
			(start 0.4318 0)
			(end 0.2032 0)
			(stroke
				(width 0.2032)
				(type default)
			)
			(layer "F.SilkS")
		)
		(fp_line
			(start -0.2032 0)
			(end -0.4191 0)
			(stroke
				(width 0.2032)
				(type default)
			)
			(layer "F.SilkS")
		)
		(fp_rect
			(start -0.635 1.1811)
			(end 0.635 -1.1811)
			(stroke
				(width 0)
				(type default)
			)
			(fill no)
			(layer "F.CrtYd")
		)
		(fp_rect
			(start -0.635 1.1811)
			(end 0.635 -1.1811)
			(stroke
				(width 0)
				(type default)
			)
			(fill no)
			(layer "F.Fab")
		)
		(pad "1" smd custom
			(at 0 -0.6604 180)
			(size 0.19685 0.19685)
			(layers "F.Cu" "F.Mask" "F.Paste")
			(net "P1V0_VDD")
			(options
				(clearance outline)
				(anchor circle)
			)
			(primitives
				(gr_poly
					(pts
						(arc
							(start 0.508 -0.2921)
							(mid 0.478242 -0.363942)
							(end 0.4064 -0.3937)
						)
						(arc
							(start -0.4064 -0.3937)
							(mid -0.478242 -0.363942)
							(end -0.508 -0.2921)
						)
						(arc
							(start -0.508 0.2921)
							(mid -0.478242 0.363942)
							(end -0.4064 0.3937)
						)
						(arc
							(start 0.4064 0.3937)
							(mid 0.478242 0.363942)
							(end 0.508 0.2921)
						)
					)
					(width 0)
					(fill yes)
				)
			)
		)
		(pad "2" smd custom
			(at 0 0.6604 180)
			(size 0.19685 0.19685)
			(layers "F.Cu" "F.Mask" "F.Paste")
			(net "P1V0_VIN")
			(options
				(clearance outline)
				(anchor circle)
			)
			(primitives
				(gr_poly
					(pts
						(arc
							(start 0.508 -0.2921)
							(mid 0.478242 -0.363942)
							(end 0.4064 -0.3937)
						)
						(arc
							(start -0.4064 -0.3937)
							(mid -0.478242 -0.363942)
							(end -0.508 -0.2921)
						)
						(arc
							(start -0.508 0.2921)
							(mid -0.478242 0.363942)
							(end -0.4064 0.3937)
						)
						(arc
							(start 0.4064 0.3937)
							(mid 0.478242 0.363942)
							(end 0.508 0.2921)
						)
					)
					(width 0)
					(fill yes)
				)
			)
		)
	)
)
